# S9S_MB_2U (Grand Teton) — schematic netlist excerpt (pin names and nets, part order shuffled) for the footprints in the layout excerpt that follows; sources: Cadence DE-HDL packaged netlist, KiCad conversion of 03242023_DA0F0TMBIJ0_F0T_Motherboard_J_brd_V01_OCP.brd

R1127  Q_RES  1K 1% EMPTY  pkg 0402LF  page 158 : A = P3V3_AUX ; B = PD_SMB_OCP1_HP_ADD0
PR1338  Q_RES  0 5% CHIP  pkg 0402LF  page 299 : A = P3V3_AUX ; B = PVPP_HBM_CPU1_VCC

(kicad_pcb
	(version 20260206)
	(generator "pcbnew")
	(generator_version "10.0")
	(general
		(thickness 1.6)
		(legacy_teardrops no)
	)
	(paper "A4")
	(title_block
		(title "03242023_DA0F0TMBIJ0_F0T_Motherboard_J_brd_V01_OCP.brd")
		(comment 1 "Grand Teton / footprints 1317-1318 of 6105")
	)
	(layers
		(0 "F.Cu" signal "TOP")
		(4 "In1.Cu" signal "GND")
		(6 "In2.Cu" signal "IN1")
		(8 "In3.Cu" signal "GND1")
		(10 "In4.Cu" signal "IN2")
		(12 "In5.Cu" signal "GND2")
		(14 "In6.Cu" signal "IN3")
		(16 "In7.Cu" signal "GND3")
		(18 "In8.Cu" signal "VCC")
		(20 "In9.Cu" signal "VCC1")
		(22 "In10.Cu" signal "GND4")
		(24 "In11.Cu" signal "IN4")
		(26 "In12.Cu" signal "GND5")
		(28 "In13.Cu" signal "IN5")
		(30 "In14.Cu" signal "GND6")
		(32 "In15.Cu" signal "IN6")
		(34 "In16.Cu" signal "GND7")
		(2 "B.Cu" signal "BOTTOM")
		(9 "F.Adhes" user "F.Adhesive")
		(11 "B.Adhes" user "B.Adhesive")
		(13 "F.Paste" user "Package Geometry/Pastemask Top")
		(15 "B.Paste" user "Package Geometry/Pastemask Bottom")
		(5 "F.SilkS" user "Ref Des/Silkscreen Top")
		(7 "B.SilkS" user "Ref Des/Silkscreen Bottom")
		(1 "F.Mask" user "Board Geometry/Soldermask Top")
		(3 "B.Mask" user "Board Geometry/Soldermask Bottom")
		(17 "Dwgs.User" user "User.Drawings")
		(19 "Cmts.User" user "User.Comments")
		(21 "Eco1.User" user "User.Eco1")
		(23 "Eco2.User" user "User.Eco2")
		(25 "Edge.Cuts" user "Board Geometry/Outline")
		(27 "Margin" user)
		(31 "F.CrtYd" user "Package Geometry/Place Bound Top")
		(29 "B.CrtYd" user "Package Geometry/Place Bound Bottom")
		(35 "F.Fab" user "Ref Des/Assembly Top")
		(33 "B.Fab" user "Ref Des/Assembly Bottom")
	)
	(footprint ""
		(layer "F.Cu")
		(at 128.948434 -361.313476 180)
		(property "Reference" "PR1338"
			(at 0 0 180)
			(layer "F.SilkS")
			(hide yes)
			(effects
				(font
					(size 1.27 1.27)
				)
			)
		)
		(property "Value" ""
			(at 0 0 180)
			(layer "F.Fab")
			(effects
				(font
					(size 1.27 1.27)
				)
			)
		)
		(duplicate_pad_numbers_are_jumpers no)
		(fp_line
			(start 0.7874 0.4064)
			(end -0.7874 0.4064)
			(stroke
				(width 0.1524)
				(type default)
			)
			(layer "F.SilkS")
		)
		(fp_line
			(start 0.7874 -0.4064)
			(end 0.7874 0.4064)
			(stroke
				(width 0.1524)
				(type default)
			)
			(layer "F.SilkS")
		)
		(fp_line
			(start -0.7874 0.4064)
			(end -0.7874 -0.4064)
			(stroke
				(width 0.1524)
				(type default)
			)
			(layer "F.SilkS")
		)
		(fp_line
			(start -0.7874 -0.4064)
			(end 0.7874 -0.4064)
			(stroke
				(width 0.1524)
				(type default)
			)
			(layer "F.SilkS")
		)
		(fp_line
			(start 0.67945 0.3048)
			(end 0.120396 0.3048)
			(stroke
				(width 0.1)
				(type default)
			)
			(layer "F.Fab")
		)
		(fp_line
			(start 0.67945 -0.3048)
			(end 0.67945 0.3048)
			(stroke
				(width 0.1)
				(type default)
			)
			(layer "F.Fab")
		)
		(fp_line
			(start 0.12065 -0.2794)
			(end 0.12065 -0.3048)
			(stroke
				(width 0.1)
				(type default)
			)
			(layer "F.Fab")
		)
		(fp_line
			(start 0.12065 -0.3048)
			(end 0.67945 -0.3048)
			(stroke
				(width 0.1)
				(type default)
			)
			(layer "F.Fab")
		)
		(fp_line
			(start 0.120396 0.3048)
			(end 0.120396 0.2794)
			(stroke
				(width 0.1)
				(type default)
			)
			(layer "F.Fab")
		)
		(fp_line
			(start 0.120396 0.2794)
			(end -0.12065 0.2794)
			(stroke
				(width 0.1)
				(type default)
			)
			(layer "F.Fab")
		)
		(fp_line
			(start -0.12065 0.3048)
			(end -0.67945 0.3048)
			(stroke
				(width 0.1)
				(type default)
			)
			(layer "F.Fab")
		)
		(fp_line
			(start -0.12065 0.2794)
			(end -0.12065 0.3048)
			(stroke
				(width 0.1)
				(type default)
			)
			(layer "F.Fab")
		)
		(fp_line
			(start -0.12065 -0.2794)
			(end 0.12065 -0.2794)
			(stroke
				(width 0.1)
				(type default)
			)
			(layer "F.Fab")
		)
		(fp_line
			(start -0.12065 -0.305054)
			(end -0.12065 -0.2794)
			(stroke
				(width 0.1)
				(type default)
			)
			(layer "F.Fab")
		)
		(fp_line
			(start -0.67945 0.3048)
			(end -0.67945 -0.305054)
			(stroke
				(width 0.1)
				(type default)
			)
			(layer "F.Fab")
		)
		(fp_line
			(start -0.67945 -0.305054)
			(end -0.12065 -0.305054)
			(stroke
				(width 0.1)
				(type default)
			)
			(layer "F.Fab")
		)
		(pad "1" smd circle
			(at -0.40005 0 180)
			(size 0 0)
			(layers "F.Cu" "F.Mask" "F.Paste")
			(net "P3V3_AUX")
		)
		(pad "2" smd circle
			(at 0.40005 0 180)
			(size 0 0)
			(layers "F.Cu" "F.Mask" "F.Paste")
			(net "PVPP_HBM_CPU1_VCC")
		)
	)
	(footprint ""
		(layer "F.Cu")
		(at 465.823554 -115.295934 180)
		(property "Reference" "R1127"
			(at 0 0 180)
			(layer "F.SilkS")
			(hide yes)
			(effects
				(font
					(size 1.27 1.27)
				)
			)
		)
		(property "Value" ""
			(at 0 0 180)
			(layer "F.Fab")
			(effects
				(font
					(size 1.27 1.27)
				)
			)
		)
		(duplicate_pad_numbers_are_jumpers no)
		(fp_line
			(start 0.7874 0.4064)
			(end -0.7874 0.4064)
			(stroke
				(width 0.1524)
				(type default)
			)
			(layer "F.SilkS")
		)
		(fp_line
			(start 0.7874 -0.4064)
			(end 0.7874 0.4064)
			(stroke
				(width 0.1524)
				(type default)
			)
			(layer "F.SilkS")
		)
		(fp_line
			(start -0.7874 0.4064)
			(end -0.7874 -0.4064)
			(stroke
				(width 0.1524)
				(type default)
			)
			(layer "F.SilkS")
		)
		(fp_line
			(start -0.7874 -0.4064)
			(end 0.7874 -0.4064)
			(stroke
				(width 0.1524)
				(type default)
			)
			(layer "F.SilkS")
		)
		(fp_line
			(start 0.67945 0.3048)
			(end 0.120396 0.3048)
			(stroke
				(width 0.1)
				(type default)
			)
			(layer "F.Fab")
		)
		(fp_line
			(start 0.67945 -0.3048)
			(end 0.67945 0.3048)
			(stroke
				(width 0.1)
				(type default)
			)
			(layer "F.Fab")
		)
		(fp_line
			(start 0.12065 -0.2794)
			(end 0.12065 -0.3048)
			(stroke
				(width 0.1)
				(type default)
			)
			(layer "F.Fab")
		)
		(fp_line
			(start 0.12065 -0.3048)
			(end 0.67945 -0.3048)
			(stroke
				(width 0.1)
				(type default)
			)
			(layer "F.Fab")
		)
		(fp_line
			(start 0.120396 0.3048)
			(end 0.120396 0.2794)
			(stroke
				(width 0.1)
				(type default)
			)
			(layer "F.Fab")
		)
		(fp_line
			(start 0.120396 0.2794)
			(end -0.12065 0.2794)
			(stroke
				(width 0.1)
				(type default)
			)
			(layer "F.Fab")
		)
		(fp_line
			(start -0.12065 0.3048)
			(end -0.67945 0.3048)
			(stroke
				(width 0.1)
				(type default)
			)
			(layer "F.Fab")
		)
		(fp_line
			(start -0.12065 0.2794)
			(end -0.12065 0.3048)
			(stroke
				(width 0.1)
				(type default)
			)
			(layer "F.Fab")
		)
		(fp_line
			(start -0.12065 -0.2794)
			(end 0.12065 -0.2794)
			(stroke
				(width 0.1)
				(type default)
			)
			(layer "F.Fab")
		)
		(fp_line
			(start -0.12065 -0.305054)
			(end -0.12065 -0.2794)
			(stroke
				(width 0.1)
				(type default)
			)
			(layer "F.Fab")
		)
		(fp_line
			(start -0.67945 0.3048)
			(end -0.67945 -0.305054)
			(stroke
				(width 0.1)
				(type default)
			)
			(layer "F.Fab")
		)
		(fp_line
			(start -0.67945 -0.305054)
			(end -0.12065 -0.305054)
			(stroke
				(width 0.1)
				(type default)
			)
			(layer "F.Fab")
		)
		(pad "1" smd circle
			(at -0.40005 0 180)
			(size 0 0)
			(layers "F.Cu" "F.Mask" "F.Paste")
			(net "P3V3_AUX")
		)
		(pad "2" smd circle
			(at 0.40005 0 180)
			(size 0 0)
			(layers "F.Cu" "F.Mask" "F.Paste")
			(net "PD_SMB_OCP1_HP_ADD0")
		)
	)
)
